# S9S_MB_2U (Grand Teton) — schematic netlist excerpt (pin names and nets, part order shuffled) for the footprints in the layout excerpt that follows; sources: Cadence DE-HDL packaged netlist, KiCad conversion of 03242023_DA0F0TMBIJ0_F0T_Motherboard_J_brd_V01_OCP.brd

PC511_P1_6  Q_CAP  22UF 16V 20% X6S  pkg C0805  page 287 : A = SW_P12V_PVCCIN_CPU1_FLT ; B = GND
C532  Q_CAP  47UF 2.5V 20% X6S  pkg C0603  page 75 : A = PVCCINFAON_CPU0 ; B = GND
R4536  Q_RES  10 1% CHIP  pkg 0402LF  page 240 : A = CLK_100M_BMC_P3E_DN ; B = CLK_100M_BMC_P3E_DN_R

(kicad_pcb
	(version 20260206)
	(generator "pcbnew")
	(generator_version "10.0")
	(general
		(thickness 1.6)
		(legacy_teardrops no)
	)
	(paper "A4")
	(title_block
		(title "03242023_DA0F0TMBIJ0_F0T_Motherboard_J_brd_V01_OCP.brd")
		(comment 1 "Grand Teton / footprints 5739-5741 of 6105")
	)
	(layers
		(0 "F.Cu" signal "TOP")
		(4 "In1.Cu" signal "GND")
		(6 "In2.Cu" signal "IN1")
		(8 "In3.Cu" signal "GND1")
		(10 "In4.Cu" signal "IN2")
		(12 "In5.Cu" signal "GND2")
		(14 "In6.Cu" signal "IN3")
		(16 "In7.Cu" signal "GND3")
		(18 "In8.Cu" signal "VCC")
		(20 "In9.Cu" signal "VCC1")
		(22 "In10.Cu" signal "GND4")
		(24 "In11.Cu" signal "IN4")
		(26 "In12.Cu" signal "GND5")
		(28 "In13.Cu" signal "IN5")
		(30 "In14.Cu" signal "GND6")
		(32 "In15.Cu" signal "IN6")
		(34 "In16.Cu" signal "GND7")
		(2 "B.Cu" signal "BOTTOM")
		(9 "F.Adhes" user "F.Adhesive")
		(11 "B.Adhes" user "B.Adhesive")
		(13 "F.Paste" user "Package Geometry/Pastemask Top")
		(15 "B.Paste" user "Package Geometry/Pastemask Bottom")
		(5 "F.SilkS" user "Ref Des/Silkscreen Top")
		(7 "B.SilkS" user "Ref Des/Silkscreen Bottom")
		(1 "F.Mask" user "Board Geometry/Soldermask Top")
		(3 "B.Mask" user "Board Geometry/Soldermask Bottom")
		(17 "Dwgs.User" user "User.Drawings")
		(19 "Cmts.User" user "User.Comments")
		(21 "Eco1.User" user "User.Eco1")
		(23 "Eco2.User" user "User.Eco2")
		(25 "Edge.Cuts" user "Board Geometry/Outline")
		(27 "Margin" user)
		(31 "F.CrtYd" user "Package Geometry/Place Bound Top")
		(29 "B.CrtYd" user "Package Geometry/Place Bound Bottom")
		(35 "F.Fab" user "Ref Des/Assembly Top")
		(33 "B.Fab" user "Ref Des/Assembly Bottom")
	)
	(footprint ""
		(layer "B.Cu")
		(at 170.20032 -13.762228 90)
		(property "Reference" "R4536"
			(at 0 0 90)
			(layer "B.SilkS")
			(hide yes)
			(effects
				(font
					(size 1.27 1.27)
				)
				(justify mirror)
			)
		)
		(property "Value" ""
			(at 0 0 90)
			(layer "B.Fab")
			(effects
				(font
					(size 1.27 1.27)
				)
				(justify mirror)
			)
		)
		(duplicate_pad_numbers_are_jumpers no)
		(fp_line
			(start 0.7874 -0.4064)
			(end -0.7874 -0.4064)
			(stroke
				(width 0.1524)
				(type default)
			)
			(layer "B.SilkS")
		)
		(fp_line
			(start -0.7874 -0.4064)
			(end -0.7874 0.14732)
			(stroke
				(width 0.1524)
				(type default)
			)
			(layer "B.SilkS")
		)
		(fp_line
			(start 0.7874 0.20574)
			(end 0.7874 -0.4064)
			(stroke
				(width 0.1524)
				(type default)
			)
			(layer "B.SilkS")
		)
		(fp_line
			(start -0.10668 0.4064)
			(end 0.40386 0.4064)
			(stroke
				(width 0.1524)
				(type default)
			)
			(layer "B.SilkS")
		)
		(fp_line
			(start 0.67945 -0.305054)
			(end 0.12065 -0.305054)
			(stroke
				(width 0.1)
				(type default)
			)
			(layer "B.Fab")
		)
		(fp_line
			(start 0.12065 -0.305054)
			(end 0.12065 -0.2794)
			(stroke
				(width 0.1)
				(type default)
			)
			(layer "B.Fab")
		)
		(fp_line
			(start -0.12065 -0.3048)
			(end -0.67945 -0.3048)
			(stroke
				(width 0.1)
				(type default)
			)
			(layer "B.Fab")
		)
		(fp_line
			(start -0.67945 -0.3048)
			(end -0.67945 0.3048)
			(stroke
				(width 0.1)
				(type default)
			)
			(layer "B.Fab")
		)
		(fp_line
			(start 0.12065 -0.2794)
			(end -0.12065 -0.2794)
			(stroke
				(width 0.1)
				(type default)
			)
			(layer "B.Fab")
		)
		(fp_line
			(start -0.12065 -0.2794)
			(end -0.12065 -0.3048)
			(stroke
				(width 0.1)
				(type default)
			)
			(layer "B.Fab")
		)
		(fp_line
			(start 0.12065 0.2794)
			(end 0.12065 0.3048)
			(stroke
				(width 0.1)
				(type default)
			)
			(layer "B.Fab")
		)
		(fp_line
			(start -0.120396 0.2794)
			(end 0.12065 0.2794)
			(stroke
				(width 0.1)
				(type default)
			)
			(layer "B.Fab")
		)
		(fp_line
			(start 0.67945 0.3048)
			(end 0.67945 -0.305054)
			(stroke
				(width 0.1)
				(type default)
			)
			(layer "B.Fab")
		)
		(fp_line
			(start 0.12065 0.3048)
			(end 0.67945 0.3048)
			(stroke
				(width 0.1)
				(type default)
			)
			(layer "B.Fab")
		)
		(fp_line
			(start -0.120396 0.3048)
			(end -0.120396 0.2794)
			(stroke
				(width 0.1)
				(type default)
			)
			(layer "B.Fab")
		)
		(fp_line
			(start -0.67945 0.3048)
			(end -0.120396 0.3048)
			(stroke
				(width 0.1)
				(type default)
			)
			(layer "B.Fab")
		)
		(pad "1" smd circle
			(at 0.40005 0 270)
			(size 0 0)
			(layers "B.Cu" "B.Mask" "B.Paste")
			(net "CLK_100M_BMC_P3E_DN")
		)
		(pad "2" smd circle
			(at -0.40005 0 270)
			(size 0 0)
			(layers "B.Cu" "B.Mask" "B.Paste")
			(net "CLK_100M_BMC_P3E_DN_R")
		)
	)
	(footprint ""
		(layer "B.Cu")
		(at 367.009934 -237.709202 -90)
		(property "Reference" "C532"
			(at 0 0 90)
			(layer "B.SilkS")
			(hide yes)
			(effects
				(font
					(size 1.27 1.27)
				)
				(justify mirror)
			)
		)
		(property "Value" ""
			(at 0 0 90)
			(layer "B.Fab")
			(effects
				(font
					(size 1.27 1.27)
				)
				(justify mirror)
			)
		)
		(duplicate_pad_numbers_are_jumpers no)
		(fp_line
			(start -1.2954 0.5842)
			(end 1.2954 0.5842)
			(stroke
				(width 0.1524)
				(type default)
			)
			(layer "B.SilkS")
		)
		(fp_line
			(start 1.2954 0.5842)
			(end 1.2954 -0.5842)
			(stroke
				(width 0.1524)
				(type default)
			)
			(layer "B.SilkS")
		)
		(fp_line
			(start -1.2954 -0.5842)
			(end -1.2954 0.5842)
			(stroke
				(width 0.1524)
				(type default)
			)
			(layer "B.SilkS")
		)
		(fp_line
			(start 0 -0.5842)
			(end 0 0.5842)
			(stroke
				(width 0.1524)
				(type default)
			)
			(layer "B.SilkS")
		)
		(fp_line
			(start 1.2954 -0.5842)
			(end -1.2954 -0.5842)
			(stroke
				(width 0.1524)
				(type default)
			)
			(layer "B.SilkS")
		)
		(fp_line
			(start -0.8636 0.4572)
			(end 0.8636 0.4572)
			(stroke
				(width 0.1)
				(type default)
			)
			(layer "B.Fab")
		)
		(fp_line
			(start 0.8636 0.4572)
			(end 0.8636 0.4064)
			(stroke
				(width 0.1)
				(type default)
			)
			(layer "B.Fab")
		)
		(fp_line
			(start -1.1938 0.4064)
			(end -0.8636 0.4064)
			(stroke
				(width 0.1)
				(type default)
			)
			(layer "B.Fab")
		)
		(fp_line
			(start -0.8636 0.4064)
			(end -0.8636 0.4572)
			(stroke
				(width 0.1)
				(type default)
			)
			(layer "B.Fab")
		)
		(fp_line
			(start 0.8636 0.4064)
			(end 1.1938 0.4064)
			(stroke
				(width 0.1)
				(type default)
			)
			(layer "B.Fab")
		)
		(fp_line
			(start 1.1938 0.4064)
			(end 1.1938 -0.4064)
			(stroke
				(width 0.1)
				(type default)
			)
			(layer "B.Fab")
		)
		(fp_line
			(start -1.1938 -0.4064)
			(end -1.1938 0.4064)
			(stroke
				(width 0.1)
				(type default)
			)
			(layer "B.Fab")
		)
		(fp_line
			(start -0.8636 -0.4064)
			(end -1.1938 -0.4064)
			(stroke
				(width 0.1)
				(type default)
			)
			(layer "B.Fab")
		)
		(fp_line
			(start 0.8636 -0.4064)
			(end 0.8636 -0.4572)
			(stroke
				(width 0.1)
				(type default)
			)
			(layer "B.Fab")
		)
		(fp_line
			(start 1.1938 -0.4064)
			(end 0.8636 -0.4064)
			(stroke
				(width 0.1)
				(type default)
			)
			(layer "B.Fab")
		)
		(fp_line
			(start -0.8636 -0.4572)
			(end -0.8636 -0.4064)
			(stroke
				(width 0.1)
				(type default)
			)
			(layer "B.Fab")
		)
		(fp_line
			(start 0.8636 -0.4572)
			(end -0.8636 -0.4572)
			(stroke
				(width 0.1)
				(type default)
			)
			(layer "B.Fab")
		)
		(pad "1" smd rect
			(at 0.7366 0 180)
			(size 0.7112 0.8128)
			(layers "B.Cu" "B.Mask" "B.Paste")
			(net "PVCCINFAON_CPU0")
		)
		(pad "2" smd rect
			(at -0.7366 0 180)
			(size 0.7112 0.8128)
			(layers "B.Cu" "B.Mask" "B.Paste")
			(net "GND")
		)
	)
	(footprint ""
		(layer "B.Cu")
		(at 92.09405 -337.145884 90)
		(property "Reference" "PC511_P1_6"
			(at 0 0 90)
			(layer "B.SilkS")
			(hide yes)
			(effects
				(font
					(size 1.27 1.27)
				)
				(justify mirror)
			)
		)
		(property "Value" ""
			(at 0 0 90)
			(layer "B.Fab")
			(effects
				(font
					(size 1.27 1.27)
				)
				(justify mirror)
			)
		)
		(duplicate_pad_numbers_are_jumpers no)
		(fp_line
			(start 1.524 -0.762)
			(end -1.524 -0.762)
			(stroke
				(width 0.1524)
				(type default)
			)
			(layer "B.SilkS")
		)
		(fp_line
			(start -1.524 -0.762)
			(end -1.524 0.762)
			(stroke
				(width 0.1524)
				(type default)
			)
			(layer "B.SilkS")
		)
		(fp_line
			(start 1.524 0.762)
			(end 1.524 -0.762)
			(stroke
				(width 0.1524)
				(type default)
			)
			(layer "B.SilkS")
		)
		(fp_line
			(start -1.524 0.762)
			(end 1.524 0.762)
			(stroke
				(width 0.1524)
				(type default)
			)
			(layer "B.SilkS")
		)
		(fp_line
			(start 1.1049 -0.724916)
			(end 1.1049 0.724916)
			(stroke
				(width 0.1)
				(type default)
			)
			(layer "B.Fab")
		)
		(fp_line
			(start -1.1049 -0.724916)
			(end 1.1049 -0.724916)
			(stroke
				(width 0.1)
				(type default)
			)
			(layer "B.Fab")
		)
		(fp_line
			(start 1.1049 0.724916)
			(end -1.1049 0.724916)
			(stroke
				(width 0.1)
				(type default)
			)
			(layer "B.Fab")
		)
		(fp_line
			(start -1.1049 0.724916)
			(end -1.1049 -0.724916)
			(stroke
				(width 0.1)
				(type default)
			)
			(layer "B.Fab")
		)
		(pad "1" smd rect
			(at 0.889 0 90)
			(size 1.016 1.27)
			(layers "B.Cu" "B.Mask" "B.Paste")
			(net "SW_P12V_PVCCIN_CPU1_FLT")
		)
		(pad "2" smd rect
			(at -0.889 0 90)
			(size 1.016 1.27)
			(layers "B.Cu" "B.Mask" "B.Paste")
			(net "GND")
		)
	)
)
